(kicad_pcb
	(version 20260206)
	(generator "pcbnew")
	(generator_version "10.0")
	(general
		(thickness 1.6)
		(legacy_teardrops no)
	)
	(paper "A4")
	(title_block
		(title "Bryce Canyon_IOM_M2_16342-2_OCP.brd")
		(comment 1 "Bryce Canyon / footprints 948-954 of 1146")
	)
	(layers
		(0 "F.Cu" signal "TOP")
		(4 "In1.Cu" signal "L2GND")
		(6 "In2.Cu" signal "L3")
		(8 "In3.Cu" signal "L4VCC")
		(10 "In4.Cu" signal "L5VCC")
		(12 "In5.Cu" signal "L6")
		(14 "In6.Cu" signal "L7GND")
		(2 "B.Cu" signal "BOTTOM")
		(9 "F.Adhes" user "F.Adhesive")
		(11 "B.Adhes" user "B.Adhesive")
		(13 "F.Paste" user "Package Geometry/Pastemask Top")
		(15 "B.Paste" user "Package Geometry/Pastemask Bottom")
		(5 "F.SilkS" user "Ref Des/Silkscreen Top")
		(7 "B.SilkS" user "Ref Des/Silkscreen Bottom")
		(1 "F.Mask" user "Board Geometry/Soldermask Top")
		(3 "B.Mask" user "Board Geometry/Soldermask Bottom")
		(17 "Dwgs.User" user "User.Drawings")
		(19 "Cmts.User" user "User.Comments")
		(21 "Eco1.User" user "User.Eco1")
		(23 "Eco2.User" user "User.Eco2")
		(25 "Edge.Cuts" user "Board Geometry/Outline")
		(27 "Margin" user)
		(31 "F.CrtYd" user "Package Geometry/Place Bound Top")
		(29 "B.CrtYd" user "Package Geometry/Place Bound Bottom")
		(35 "F.Fab" user "Ref Des/Assembly Top")
		(33 "B.Fab" user "Ref Des/Assembly Bottom")
	)
	(footprint ""
		(layer "B.Cu")
		(at 208.0514 -99.5426 180)
		(property "Reference" "R526"
			(at 0 0 0)
			(layer "B.SilkS")
			(hide yes)
			(effects
				(font
					(size 1.27 1.27)
				)
				(justify mirror)
			)
		)
		(property "Value" "0R2J-2-GP"
			(at -0.064008 -3.993896 180)
			(unlocked yes)
			(layer "B.Fab")
			(hide yes)
			(effects
				(font
					(size 1.016 1.016)
					(thickness 0.1524)
				)
				(justify mirror)
			)
		)
		(property "Device Type" "R402H16"
			(at -0.064008 -5.517896 180)
			(unlocked yes)
			(layer "B.Fab")
			(hide yes)
			(effects
				(font
					(size 1.016 1.016)
					(thickness 0.1524)
				)
				(justify mirror)
			)
		)
		(duplicate_pad_numbers_are_jumpers no)
		(fp_line
			(start 0.508 -0.9398)
			(end 0.508 0.9398)
			(stroke
				(width 0.1524)
				(type default)
			)
			(layer "B.SilkS")
		)
		(fp_line
			(start -0.508 -0.9398)
			(end 0.508 -0.9398)
			(stroke
				(width 0.1524)
				(type default)
			)
			(layer "B.SilkS")
		)
		(fp_rect
			(start 0.508 0.9398)
			(end -0.508 -0.9398)
			(stroke
				(width 0)
				(type default)
			)
			(fill no)
			(layer "B.CrtYd")
		)
		(fp_rect
			(start 0.508 0.9398)
			(end -0.508 -0.9398)
			(stroke
				(width 0)
				(type default)
			)
			(fill no)
			(layer "B.Fab")
		)
		(pad "1" smd custom
			(at 0 -0.4445)
			(size 0.1397 0.1397)
			(layers "B.Cu" "B.Mask" "B.Paste")
			(net "IOM_FULL_PGOOD")
			(options
				(clearance outline)
				(anchor circle)
			)
			(primitives
				(gr_poly
					(pts
						(arc
							(start -0.1778 0.2794)
							(mid -0.249642 0.249642)
							(end -0.2794 0.1778)
						)
						(arc
							(start -0.2794 -0.1778)
							(mid -0.249642 -0.249642)
							(end -0.1778 -0.2794)
						)
						(arc
							(start 0.1778 -0.2794)
							(mid 0.249642 -0.249642)
							(end 0.2794 -0.1778)
						)
						(arc
							(start 0.2794 0.1778)
							(mid 0.249642 0.249642)
							(end 0.1778 0.2794)
						)
					)
					(width 0)
					(fill yes)
				)
			)
		)
		(pad "2" smd custom
			(at 0 0.4445)
			(size 0.1397 0.1397)
			(layers "B.Cu" "B.Mask" "B.Paste")
			(net "U82_VREF2")
			(options
				(clearance outline)
				(anchor circle)
			)
			(primitives
				(gr_poly
					(pts
						(arc
							(start -0.1778 0.2794)
							(mid -0.249642 0.249642)
							(end -0.2794 0.1778)
						)
						(arc
							(start -0.2794 -0.1778)
							(mid -0.249642 -0.249642)
							(end -0.1778 -0.2794)
						)
						(arc
							(start 0.1778 -0.2794)
							(mid 0.249642 -0.249642)
							(end 0.2794 -0.1778)
						)
						(arc
							(start 0.2794 0.1778)
							(mid 0.249642 0.249642)
							(end 0.1778 0.2794)
						)
					)
					(width 0)
					(fill yes)
				)
			)
		)
	)
	(footprint ""
		(layer "B.Cu")
		(at 38.0238 -182.6768 180)
		(property "Reference" "R484"
			(at 0 0 0)
			(layer "B.SilkS")
			(hide yes)
			(effects
				(font
					(size 1.27 1.27)
				)
				(justify mirror)
			)
		)
		(property "Value" "3D01R5F-GP"
			(at 0 -8.9535 180)
			(unlocked yes)
			(layer "B.Fab")
			(hide yes)
			(effects
				(font
					(size 1.27 1.016)
					(thickness 0.1524)
				)
				(justify mirror)
			)
		)
		(property "Device Type" "R805H24"
			(at 0 -10.6299 180)
			(unlocked yes)
			(layer "B.Fab")
			(hide yes)
			(effects
				(font
					(size 1.27 1.016)
					(thickness 0.1524)
				)
				(justify mirror)
			)
		)
		(duplicate_pad_numbers_are_jumpers no)
		(fp_line
			(start 0.889 1.7018)
			(end -0.889 1.7018)
			(stroke
				(width 0.1524)
				(type default)
			)
			(layer "B.SilkS")
		)
		(fp_line
			(start 0.889 0.0762)
			(end 0.889 1.7018)
			(stroke
				(width 0.1524)
				(type default)
			)
			(layer "B.SilkS")
		)
		(fp_line
			(start 0.889 -1.7018)
			(end 0.889 0.2794)
			(stroke
				(width 0.1524)
				(type default)
			)
			(layer "B.SilkS")
		)
		(fp_line
			(start -0.889 1.7018)
			(end -0.889 -0.508)
			(stroke
				(width 0.1524)
				(type default)
			)
			(layer "B.SilkS")
		)
		(fp_line
			(start -0.889 -1.7018)
			(end 0.889 -1.7018)
			(stroke
				(width 0.1524)
				(type default)
			)
			(layer "B.SilkS")
		)
		(fp_line
			(start -0.889 -1.7018)
			(end -0.889 -0.381)
			(stroke
				(width 0.1524)
				(type default)
			)
			(layer "B.SilkS")
		)
		(fp_poly
			(pts
				(xy -0.9652 -1.778) (xy -0.9652 1.778) (xy 0.9652 1.778) (xy 0.9652 -1.778)
			)
			(stroke
				(width 0)
				(type default)
			)
			(fill no)
			(layer "B.CrtYd")
		)
		(fp_rect
			(start 0.9652 1.778)
			(end -0.9652 -1.778)
			(stroke
				(width 0)
				(type default)
			)
			(fill no)
			(layer "B.Fab")
		)
		(pad "1" smd rect
			(at 0 -0.9652)
			(size 1.397 1.143)
			(layers "B.Cu" "B.Mask" "B.Paste")
			(net "P3V3_VBST")
		)
		(pad "2" smd rect
			(at 0 0.9652)
			(size 1.397 1.143)
			(layers "B.Cu" "B.Mask" "B.Paste")
			(net "P3V3_VBST_RC")
		)
	)
	(footprint ""
		(layer "B.Cu")
		(at 34.8234 -152.0952 180)
		(property "Reference" "C94"
			(at 0 0 0)
			(layer "B.SilkS")
			(hide yes)
			(effects
				(font
					(size 1.27 1.27)
				)
				(justify mirror)
			)
		)
		(property "Value" "SC100P50V2JN-3GP"
			(at -1.1811 -2.7051 180)
			(unlocked yes)
			(layer "B.Fab")
			(hide yes)
			(effects
				(font
					(size 1.016 1.016)
					(thickness 0.1524)
				)
				(justify mirror)
			)
		)
		(property "Device Type" "C402H22"
			(at -1.1811 -4.2291 180)
			(unlocked yes)
			(layer "B.Fab")
			(hide yes)
			(effects
				(font
					(size 1.016 1.016)
					(thickness 0.1524)
				)
				(justify mirror)
			)
		)
		(duplicate_pad_numbers_are_jumpers no)
		(fp_rect
			(start 0.4318 0.9525)
			(end -0.4318 -0.9525)
			(stroke
				(width 0)
				(type default)
			)
			(fill no)
			(layer "B.CrtYd")
		)
		(fp_rect
			(start 0.4318 0.9525)
			(end -0.4318 -0.9525)
			(stroke
				(width 0)
				(type default)
			)
			(fill no)
			(layer "B.Fab")
		)
		(pad "1" smd custom
			(at 0 -0.4445)
			(size 0.1524 0.1524)
			(layers "B.Cu" "B.Mask" "B.Paste")
			(net "MPLLAV33")
			(options
				(clearance outline)
				(anchor circle)
			)
			(primitives
				(gr_poly
					(pts
						(arc
							(start 0.3048 0.2032)
							(mid 0.275042 0.275042)
							(end 0.2032 0.3048)
						)
						(arc
							(start -0.2032 0.3048)
							(mid -0.275042 0.275042)
							(end -0.3048 0.2032)
						)
						(arc
							(start -0.3048 -0.2032)
							(mid -0.275042 -0.275042)
							(end -0.2032 -0.3048)
						)
						(arc
							(start 0.2032 -0.3048)
							(mid 0.275042 -0.275042)
							(end 0.3048 -0.2032)
						)
					)
					(width 0)
					(fill yes)
				)
			)
		)
		(pad "2" smd custom
			(at 0 0.4445)
			(size 0.1524 0.1524)
			(layers "B.Cu" "B.Mask" "B.Paste")
			(net "GND")
			(options
				(clearance outline)
				(anchor circle)
			)
			(primitives
				(gr_poly
					(pts
						(arc
							(start 0.3048 0.2032)
							(mid 0.275042 0.275042)
							(end 0.2032 0.3048)
						)
						(arc
							(start -0.2032 0.3048)
							(mid -0.275042 0.275042)
							(end -0.3048 0.2032)
						)
						(arc
							(start -0.3048 -0.2032)
							(mid -0.275042 -0.275042)
							(end -0.2032 -0.3048)
						)
						(arc
							(start 0.2032 -0.3048)
							(mid 0.275042 -0.275042)
							(end 0.3048 -0.2032)
						)
					)
					(width 0)
					(fill yes)
				)
			)
		)
	)
	(footprint ""
		(layer "B.Cu")
		(at 87.8586 -146.0246 90)
		(property "Reference" "R424"
			(at 0 0 90)
			(layer "B.SilkS")
			(hide yes)
			(effects
				(font
					(size 1.27 1.27)
				)
				(justify mirror)
			)
		)
		(property "Value" "4K7R2F-GP"
			(at -0.064008 -3.993896 90)
			(unlocked yes)
			(layer "B.Fab")
			(hide yes)
			(effects
				(font
					(size 1.016 1.016)
					(thickness 0.1524)
				)
				(justify mirror)
			)
		)
		(property "Device Type" "R402H16"
			(at -0.064008 -5.517896 90)
			(unlocked yes)
			(layer "B.Fab")
			(hide yes)
			(effects
				(font
					(size 1.016 1.016)
					(thickness 0.1524)
				)
				(justify mirror)
			)
		)
		(duplicate_pad_numbers_are_jumpers no)
		(fp_line
			(start 0.508 -0.9398)
			(end 0.508 0.9398)
			(stroke
				(width 0.1524)
				(type default)
			)
			(layer "B.SilkS")
		)
		(fp_line
			(start -0.508 -0.9398)
			(end 0.508 -0.9398)
			(stroke
				(width 0.1524)
				(type default)
			)
			(layer "B.SilkS")
		)
		(fp_rect
			(start 0.508 0.9398)
			(end -0.508 -0.9398)
			(stroke
				(width 0)
				(type default)
			)
			(fill no)
			(layer "B.CrtYd")
		)
		(fp_rect
			(start 0.508 0.9398)
			(end -0.508 -0.9398)
			(stroke
				(width 0)
				(type default)
			)
			(fill no)
			(layer "B.Fab")
		)
		(pad "1" smd custom
			(at 0 -0.4445 270)
			(size 0.1397 0.1397)
			(layers "B.Cu" "B.Mask" "B.Paste")
			(net "P3V3_STBY")
			(options
				(clearance outline)
				(anchor circle)
			)
			(primitives
				(gr_poly
					(pts
						(arc
							(start -0.1778 0.2794)
							(mid -0.249642 0.249642)
							(end -0.2794 0.1778)
						)
						(arc
							(start -0.2794 -0.1778)
							(mid -0.249642 -0.249642)
							(end -0.1778 -0.2794)
						)
						(arc
							(start 0.1778 -0.2794)
							(mid 0.249642 -0.249642)
							(end 0.2794 -0.1778)
						)
						(arc
							(start 0.2794 0.1778)
							(mid 0.249642 0.249642)
							(end 0.1778 0.2794)
						)
					)
					(width 0)
					(fill yes)
				)
			)
		)
		(pad "2" smd custom
			(at 0 0.4445 270)
			(size 0.1397 0.1397)
			(layers "B.Cu" "B.Mask" "B.Paste")
			(net "TCA9555_A1")
			(options
				(clearance outline)
				(anchor circle)
			)
			(primitives
				(gr_poly
					(pts
						(arc
							(start -0.1778 0.2794)
							(mid -0.249642 0.249642)
							(end -0.2794 0.1778)
						)
						(arc
							(start -0.2794 -0.1778)
							(mid -0.249642 -0.249642)
							(end -0.1778 -0.2794)
						)
						(arc
							(start 0.1778 -0.2794)
							(mid 0.249642 -0.249642)
							(end 0.2794 -0.1778)
						)
						(arc
							(start 0.2794 0.1778)
							(mid 0.249642 0.249642)
							(end 0.1778 0.2794)
						)
					)
					(width 0)
					(fill yes)
				)
			)
		)
	)
	(footprint ""
		(layer "B.Cu")
		(at 37.228018 -143.050514)
		(property "Reference" "C59"
			(at 0 0 0)
			(layer "B.SilkS")
			(hide yes)
			(effects
				(font
					(size 1.27 1.27)
				)
				(justify mirror)
			)
		)
		(property "Value" "SC1U16V3KX-5GP"
			(at 0 -2.8194 0)
			(unlocked yes)
			(layer "B.Fab")
			(hide yes)
			(effects
				(font
					(size 1.016 1.016)
					(thickness 0.1524)
				)
				(justify mirror)
			)
		)
		(property "Device Type" "C603H36"
			(at 0 -4.3434 0)
			(unlocked yes)
			(layer "B.Fab")
			(hide yes)
			(effects
				(font
					(size 1.016 1.016)
					(thickness 0.1524)
				)
				(justify mirror)
			)
		)
		(duplicate_pad_numbers_are_jumpers no)
		(fp_line
			(start -0.508 0)
			(end 0.508 0)
			(stroke
				(width 0.2032)
				(type default)
			)
			(layer "B.SilkS")
		)
		(fp_rect
			(start 0.5842 1.3335)
			(end -0.5842 -1.3335)
			(stroke
				(width 0)
				(type default)
			)
			(fill no)
			(layer "B.CrtYd")
		)
		(fp_rect
			(start 0.5842 1.3335)
			(end -0.5842 -1.3335)
			(stroke
				(width 0)
				(type default)
			)
			(fill no)
			(layer "B.Fab")
		)
		(pad "1" smd custom
			(at 0 -0.762 180)
			(size 0.2159 0.2159)
			(layers "B.Cu" "B.Mask" "B.Paste")
			(net "P1V2_STBY")
			(options
				(clearance outline)
				(anchor circle)
			)
			(primitives
				(gr_poly
					(pts
						(arc
							(start -0.3302 0.4318)
							(mid -0.402042 0.402042)
							(end -0.4318 0.3302)
						)
						(arc
							(start -0.4318 -0.3302)
							(mid -0.402042 -0.402042)
							(end -0.3302 -0.4318)
						)
						(arc
							(start 0.3302 -0.4318)
							(mid 0.402042 -0.402042)
							(end 0.4318 -0.3302)
						)
						(arc
							(start 0.4318 0.3302)
							(mid 0.402042 0.402042)
							(end 0.3302 0.4318)
						)
					)
					(width 0)
					(fill yes)
				)
			)
		)
		(pad "2" smd custom
			(at 0 0.762 180)
			(size 0.2159 0.2159)
			(layers "B.Cu" "B.Mask" "B.Paste")
			(net "GND")
			(options
				(clearance outline)
				(anchor circle)
			)
			(primitives
				(gr_poly
					(pts
						(arc
							(start -0.3302 0.4318)
							(mid -0.402042 0.402042)
							(end -0.4318 0.3302)
						)
						(arc
							(start -0.4318 -0.3302)
							(mid -0.402042 -0.402042)
							(end -0.3302 -0.4318)
						)
						(arc
							(start 0.3302 -0.4318)
							(mid 0.402042 -0.402042)
							(end 0.4318 -0.3302)
						)
						(arc
							(start 0.4318 0.3302)
							(mid 0.402042 0.402042)
							(end 0.3302 0.4318)
						)
					)
					(width 0)
					(fill yes)
				)
			)
		)
	)
	(footprint ""
		(layer "B.Cu")
		(at 57.365392 -147.743164 90)
		(property "Reference" "R365"
			(at 0 0 90)
			(layer "B.SilkS")
			(hide yes)
			(effects
				(font
					(size 1.27 1.27)
				)
				(justify mirror)
			)
		)
		(property "Value" "4K7R2F-GP"
			(at -0.064008 -3.993896 90)
			(unlocked yes)
			(layer "B.Fab")
			(hide yes)
			(effects
				(font
					(size 1.016 1.016)
					(thickness 0.1524)
				)
				(justify mirror)
			)
		)
		(property "Device Type" "R402H16"
			(at -0.064008 -5.517896 90)
			(unlocked yes)
			(layer "B.Fab")
			(hide yes)
			(effects
				(font
					(size 1.016 1.016)
					(thickness 0.1524)
				)
				(justify mirror)
			)
		)
		(duplicate_pad_numbers_are_jumpers no)
		(fp_line
			(start 0.508 -0.9398)
			(end 0.508 0.9398)
			(stroke
				(width 0.1524)
				(type default)
			)
			(layer "B.SilkS")
		)
		(fp_line
			(start -0.508 -0.9398)
			(end 0.508 -0.9398)
			(stroke
				(width 0.1524)
				(type default)
			)
			(layer "B.SilkS")
		)
		(fp_rect
			(start 0.508 0.9398)
			(end -0.508 -0.9398)
			(stroke
				(width 0)
				(type default)
			)
			(fill no)
			(layer "B.CrtYd")
		)
		(fp_rect
			(start 0.508 0.9398)
			(end -0.508 -0.9398)
			(stroke
				(width 0)
				(type default)
			)
			(fill no)
			(layer "B.Fab")
		)
		(pad "1" smd custom
			(at 0 -0.4445 270)
			(size 0.1397 0.1397)
			(layers "B.Cu" "B.Mask" "B.Paste")
			(net "BMC0_JTAG_RTCK")
			(options
				(clearance outline)
				(anchor circle)
			)
			(primitives
				(gr_poly
					(pts
						(arc
							(start -0.1778 0.2794)
							(mid -0.249642 0.249642)
							(end -0.2794 0.1778)
						)
						(arc
							(start -0.2794 -0.1778)
							(mid -0.249642 -0.249642)
							(end -0.1778 -0.2794)
						)
						(arc
							(start 0.1778 -0.2794)
							(mid 0.249642 -0.249642)
							(end 0.2794 -0.1778)
						)
						(arc
							(start 0.2794 0.1778)
							(mid 0.249642 0.249642)
							(end 0.1778 0.2794)
						)
					)
					(width 0)
					(fill yes)
				)
			)
		)
		(pad "2" smd custom
			(at 0 0.4445 270)
			(size 0.1397 0.1397)
			(layers "B.Cu" "B.Mask" "B.Paste")
			(net "GND")
			(options
				(clearance outline)
				(anchor circle)
			)
			(primitives
				(gr_poly
					(pts
						(arc
							(start -0.1778 0.2794)
							(mid -0.249642 0.249642)
							(end -0.2794 0.1778)
						)
						(arc
							(start -0.2794 -0.1778)
							(mid -0.249642 -0.249642)
							(end -0.1778 -0.2794)
						)
						(arc
							(start 0.1778 -0.2794)
							(mid 0.249642 -0.249642)
							(end 0.2794 -0.1778)
						)
						(arc
							(start 0.2794 0.1778)
							(mid 0.249642 0.249642)
							(end 0.1778 0.2794)
						)
					)
					(width 0)
					(fill yes)
				)
			)
		)
	)
	(footprint ""
		(layer "B.Cu")
		(at 20.37715 -140.808202 -90)
		(property "Reference" "R206"
			(at 0 0 90)
			(layer "B.SilkS")
			(hide yes)
			(effects
				(font
					(size 1.27 1.27)
				)
				(justify mirror)
			)
		)
		(property "Value" "60D4R2F-GP"
			(at -0.064008 -3.993896 270)
			(unlocked yes)
			(layer "B.Fab")
			(hide yes)
			(effects
				(font
					(size 1.016 1.016)
					(thickness 0.1524)
				)
				(justify mirror)
			)
		)
		(property "Device Type" "R402H16"
			(at -0.064008 -5.517896 270)
			(unlocked yes)
			(layer "B.Fab")
			(hide yes)
			(effects
				(font
					(size 1.016 1.016)
					(thickness 0.1524)
				)
				(justify mirror)
			)
		)
		(duplicate_pad_numbers_are_jumpers no)
		(fp_line
			(start -0.508 -0.9398)
			(end 0.508 -0.9398)
			(stroke
				(width 0.1524)
				(type default)
			)
			(layer "B.SilkS")
		)
		(fp_line
			(start 0.508 -0.9398)
			(end 0.508 0.9398)
			(stroke
				(width 0.1524)
				(type default)
			)
			(layer "B.SilkS")
		)
		(fp_rect
			(start 0.508 0.9398)
			(end -0.508 -0.9398)
			(stroke
				(width 0)
				(type default)
			)
			(fill no)
			(layer "B.CrtYd")
		)
		(fp_rect
			(start 0.508 0.9398)
			(end -0.508 -0.9398)
			(stroke
				(width 0)
				(type default)
			)
			(fill no)
			(layer "B.Fab")
		)
		(pad "1" smd custom
			(at 0 -0.4445 90)
			(size 0.1397 0.1397)
			(layers "B.Cu" "B.Mask" "B.Paste")
			(net "MEMCK_N")
			(options
				(clearance outline)
				(anchor circle)
			)
			(primitives
				(gr_poly
					(pts
						(arc
							(start -0.1778 0.2794)
							(mid -0.249642 0.249642)
							(end -0.2794 0.1778)
						)
						(arc
							(start -0.2794 -0.1778)
							(mid -0.249642 -0.249642)
							(end -0.1778 -0.2794)
						)
						(arc
							(start 0.1778 -0.2794)
							(mid 0.249642 -0.249642)
							(end 0.2794 -0.1778)
						)
						(arc
							(start 0.2794 0.1778)
							(mid 0.249642 0.249642)
							(end 0.1778 0.2794)
						)
					)
					(width 0)
					(fill yes)
				)
			)
		)
		(pad "2" smd custom
			(at 0 0.4445 90)
			(size 0.1397 0.1397)
			(layers "B.Cu" "B.Mask" "B.Paste")
			(net "MEMCK_TER")
			(options
				(clearance outline)
				(anchor circle)
			)
			(primitives
				(gr_poly
					(pts
						(arc
							(start -0.1778 0.2794)
							(mid -0.249642 0.249642)
							(end -0.2794 0.1778)
						)
						(arc
							(start -0.2794 -0.1778)
							(mid -0.249642 -0.249642)
							(end -0.1778 -0.2794)
						)
						(arc
							(start 0.1778 -0.2794)
							(mid 0.249642 -0.249642)
							(end 0.2794 -0.1778)
						)
						(arc
							(start 0.2794 0.1778)
							(mid 0.249642 0.249642)
							(end 0.1778 0.2794)
						)
					)
					(width 0)
					(fill yes)
				)
			)
		)
	)
)
